FILE_TYPE = MULTI_PHYS_TABLE;

PART '9FGL0251DKILFT'

{========================================================================================}
:VALUE            | PART_TYPE | MATERIAL | PART_NUMBER    = STANDARD        | LIFECYCLE          | PART_NUMBER   | JEDEC_TYPE              | DESCRIPTION                     | MANUFTR | MANUF_PN         | RD_CMPLS_LVL | CMPLS_LVL | FROM_PJ     | CLASS | DIP_SMD | DATA                     | EE_CHECK_LIST | FP_ECN | PSL | CREATOR | STATUS | MSD | ESD_CDM | ESD_HBM | ESD_MM | PIN_LENGTH_SHORT_PIN | PIN_LENGTH_LONG_PIN | CREATEDAY  ;
{========================================================================================}
 '9FGL0251DKILFT' | 'SMLF'    | 'IC'     | 'AL000251002'(!) = ''               | ''               | 'AL000251002' |'VFQFPN24_TH_0-5_4X4XI'| 'IC(24P)9FGL0251DKILFT(VFQFPN)' | 'RTT'   | '9FGL0251DKILFT' | 'EP(V1)'     | ''        | 'S7G-DAVID' | 'IC'  | ''      | 'RTT_9FGL0251DKILFT.pdf' | ''            | ''     | ''  | ''      | ''     | ''  | ''      | ''      | ''     | '0 MILS'             | '0 MILS'            | '20221223'
 '9FGL0251DKILFT' | 'SMLF'    | 'EMPTY'  | 'AL000251002'(!) = ''               | ''               | 'AL000251002' |'VFQFPN24_TH_0-5_4X4XI'| 'IC(24P)9FGL0251DKILFT(VFQFPN)' | 'RTT'   | '9FGL0251DKILFT' | 'EP(V1)'     | ''        | 'S7G-DAVID' | 'IC'  | ''      | 'RTT_9FGL0251DKILFT.pdf' | ''            | ''     | ''  | ''      | ''     | ''  | ''      | ''      | ''     | '0 MILS'             | '0 MILS'            | '20221223'

END_PART

END.

